(kicad_pcb
	(version 20260206)
	(generator "pcbnew")
	(generator_version "10.0")
	(general
		(thickness 1.6)
		(legacy_teardrops no)
	)
	(paper "A4")
	(title_block
		(title "01162023_DA0F0TEBIF0_F0T_Expander_BD_F_brd_V02_OCP.brd")
		(comment 1 "Grand Teton / footprints 542-547 of 9728")
	)
	(layers
		(0 "F.Cu" signal "TOP")
		(4 "In1.Cu" signal "GND")
		(6 "In2.Cu" signal "VCC")
		(8 "In3.Cu" signal "VCC1")
		(10 "In4.Cu" signal "GND1")
		(12 "In5.Cu" signal "IN1")
		(14 "In6.Cu" signal "GND2")
		(16 "In7.Cu" signal "IN2")
		(18 "In8.Cu" signal "GND3")
		(20 "In9.Cu" signal "IN3")
		(22 "In10.Cu" signal "GND4")
		(24 "In11.Cu" signal "IN4")
		(26 "In12.Cu" signal "GND5")
		(28 "In13.Cu" signal "IN5")
		(30 "In14.Cu" signal "GND6")
		(32 "In15.Cu" signal "IN6")
		(34 "In16.Cu" signal "GND7")
		(2 "B.Cu" signal "BOTTOM")
		(9 "F.Adhes" user "F.Adhesive")
		(11 "B.Adhes" user "B.Adhesive")
		(13 "F.Paste" user "Package Geometry/Pastemask Top")
		(15 "B.Paste" user "Package Geometry/Pastemask Bottom")
		(5 "F.SilkS" user "Ref Des/Silkscreen Top")
		(7 "B.SilkS" user "Ref Des/Silkscreen Bottom")
		(1 "F.Mask" user "Board Geometry/Soldermask Top")
		(3 "B.Mask" user "Board Geometry/Soldermask Bottom")
		(17 "Dwgs.User" user "User.Drawings")
		(19 "Cmts.User" user "User.Comments")
		(21 "Eco1.User" user "User.Eco1")
		(23 "Eco2.User" user "User.Eco2")
		(25 "Edge.Cuts" user "Board Geometry/Outline")
		(27 "Margin" user)
		(31 "F.CrtYd" user "Package Geometry/Place Bound Top")
		(29 "B.CrtYd" user "Package Geometry/Place Bound Bottom")
		(35 "F.Fab" user "Ref Des/Assembly Top")
		(33 "B.Fab" user "Ref Des/Assembly Bottom")
	)
	(footprint ""
		(layer "F.Cu")
		(at 394.474954 -48.753014 180)
		(property "Reference" "C406"
			(at 0 0 180)
			(layer "F.SilkS")
			(hide yes)
			(effects
				(font
					(size 1.27 1.27)
				)
			)
		)
		(property "Value" ""
			(at 0 0 180)
			(layer "F.Fab")
			(effects
				(font
					(size 1.27 1.27)
				)
			)
		)
		(duplicate_pad_numbers_are_jumpers no)
		(fp_line
			(start 0.7874 0.4064)
			(end -0.7874 0.4064)
			(stroke
				(width 0.1524)
				(type default)
			)
			(layer "F.SilkS")
		)
		(fp_line
			(start 0.7874 -0.4064)
			(end 0.7874 0.4064)
			(stroke
				(width 0.1524)
				(type default)
			)
			(layer "F.SilkS")
		)
		(fp_line
			(start -0.7874 0.4064)
			(end -0.7874 -0.4064)
			(stroke
				(width 0.1524)
				(type default)
			)
			(layer "F.SilkS")
		)
		(fp_line
			(start -0.7874 -0.4064)
			(end 0.7874 -0.4064)
			(stroke
				(width 0.1524)
				(type default)
			)
			(layer "F.SilkS")
		)
		(fp_line
			(start 0.67945 0.3048)
			(end 0.120396 0.3048)
			(stroke
				(width 0.1)
				(type default)
			)
			(layer "F.Fab")
		)
		(fp_line
			(start 0.67945 -0.3048)
			(end 0.67945 0.3048)
			(stroke
				(width 0.1)
				(type default)
			)
			(layer "F.Fab")
		)
		(fp_line
			(start 0.12065 -0.2794)
			(end 0.12065 -0.3048)
			(stroke
				(width 0.1)
				(type default)
			)
			(layer "F.Fab")
		)
		(fp_line
			(start 0.12065 -0.3048)
			(end 0.67945 -0.3048)
			(stroke
				(width 0.1)
				(type default)
			)
			(layer "F.Fab")
		)
		(fp_line
			(start 0.120396 0.3048)
			(end 0.120396 0.2794)
			(stroke
				(width 0.1)
				(type default)
			)
			(layer "F.Fab")
		)
		(fp_line
			(start 0.120396 0.2794)
			(end -0.12065 0.2794)
			(stroke
				(width 0.1)
				(type default)
			)
			(layer "F.Fab")
		)
		(fp_line
			(start -0.12065 0.3048)
			(end -0.67945 0.3048)
			(stroke
				(width 0.1)
				(type default)
			)
			(layer "F.Fab")
		)
		(fp_line
			(start -0.12065 0.2794)
			(end -0.12065 0.3048)
			(stroke
				(width 0.1)
				(type default)
			)
			(layer "F.Fab")
		)
		(fp_line
			(start -0.12065 -0.2794)
			(end 0.12065 -0.2794)
			(stroke
				(width 0.1)
				(type default)
			)
			(layer "F.Fab")
		)
		(fp_line
			(start -0.12065 -0.305054)
			(end -0.12065 -0.2794)
			(stroke
				(width 0.1)
				(type default)
			)
			(layer "F.Fab")
		)
		(fp_line
			(start -0.67945 0.3048)
			(end -0.67945 -0.305054)
			(stroke
				(width 0.1)
				(type default)
			)
			(layer "F.Fab")
		)
		(fp_line
			(start -0.67945 -0.305054)
			(end -0.12065 -0.305054)
			(stroke
				(width 0.1)
				(type default)
			)
			(layer "F.Fab")
		)
		(pad "1" smd circle
			(at -0.40005 0 180)
			(size 0 0)
			(layers "F.Cu" "F.Mask" "F.Paste")
			(net "P3V3_AUX")
		)
		(pad "2" smd circle
			(at 0.40005 0 180)
			(size 0 0)
			(layers "F.Cu" "F.Mask" "F.Paste")
			(net "GND")
		)
	)
	(footprint ""
		(layer "F.Cu")
		(at 396.209266 -83.785202 180)
		(property "Reference" "R1757"
			(at 0 0 180)
			(layer "F.SilkS")
			(hide yes)
			(effects
				(font
					(size 1.27 1.27)
				)
			)
		)
		(property "Value" ""
			(at 0 0 180)
			(layer "F.Fab")
			(effects
				(font
					(size 1.27 1.27)
				)
			)
		)
		(duplicate_pad_numbers_are_jumpers no)
		(fp_line
			(start 0.7874 0.4064)
			(end -0.7874 0.4064)
			(stroke
				(width 0.1524)
				(type default)
			)
			(layer "F.SilkS")
		)
		(fp_line
			(start 0.7874 -0.4064)
			(end 0.7874 0.4064)
			(stroke
				(width 0.1524)
				(type default)
			)
			(layer "F.SilkS")
		)
		(fp_line
			(start -0.7874 0.4064)
			(end -0.7874 -0.4064)
			(stroke
				(width 0.1524)
				(type default)
			)
			(layer "F.SilkS")
		)
		(fp_line
			(start -0.7874 -0.4064)
			(end 0.7874 -0.4064)
			(stroke
				(width 0.1524)
				(type default)
			)
			(layer "F.SilkS")
		)
		(fp_line
			(start 0.67945 0.3048)
			(end 0.120396 0.3048)
			(stroke
				(width 0.1)
				(type default)
			)
			(layer "F.Fab")
		)
		(fp_line
			(start 0.67945 -0.3048)
			(end 0.67945 0.3048)
			(stroke
				(width 0.1)
				(type default)
			)
			(layer "F.Fab")
		)
		(fp_line
			(start 0.12065 -0.2794)
			(end 0.12065 -0.3048)
			(stroke
				(width 0.1)
				(type default)
			)
			(layer "F.Fab")
		)
		(fp_line
			(start 0.12065 -0.3048)
			(end 0.67945 -0.3048)
			(stroke
				(width 0.1)
				(type default)
			)
			(layer "F.Fab")
		)
		(fp_line
			(start 0.120396 0.3048)
			(end 0.120396 0.2794)
			(stroke
				(width 0.1)
				(type default)
			)
			(layer "F.Fab")
		)
		(fp_line
			(start 0.120396 0.2794)
			(end -0.12065 0.2794)
			(stroke
				(width 0.1)
				(type default)
			)
			(layer "F.Fab")
		)
		(fp_line
			(start -0.12065 0.3048)
			(end -0.67945 0.3048)
			(stroke
				(width 0.1)
				(type default)
			)
			(layer "F.Fab")
		)
		(fp_line
			(start -0.12065 0.2794)
			(end -0.12065 0.3048)
			(stroke
				(width 0.1)
				(type default)
			)
			(layer "F.Fab")
		)
		(fp_line
			(start -0.12065 -0.2794)
			(end 0.12065 -0.2794)
			(stroke
				(width 0.1)
				(type default)
			)
			(layer "F.Fab")
		)
		(fp_line
			(start -0.12065 -0.305054)
			(end -0.12065 -0.2794)
			(stroke
				(width 0.1)
				(type default)
			)
			(layer "F.Fab")
		)
		(fp_line
			(start -0.67945 0.3048)
			(end -0.67945 -0.305054)
			(stroke
				(width 0.1)
				(type default)
			)
			(layer "F.Fab")
		)
		(fp_line
			(start -0.67945 -0.305054)
			(end -0.12065 -0.305054)
			(stroke
				(width 0.1)
				(type default)
			)
			(layer "F.Fab")
		)
		(pad "1" smd circle
			(at -0.40005 0 180)
			(size 0 0)
			(layers "F.Cu" "F.Mask" "F.Paste")
			(net "P3V3_AUX")
		)
		(pad "2" smd circle
			(at 0.40005 0 180)
			(size 0 0)
			(layers "F.Cu" "F.Mask" "F.Paste")
			(net "SMB_BIC_I2C6_MUX_CLK_R_SCL")
		)
	)
	(footprint ""
		(layer "F.Cu")
		(at 246.82704 -258.039616 -90)
		(property "Reference" "R6529"
			(at 0 0 270)
			(layer "F.SilkS")
			(hide yes)
			(effects
				(font
					(size 1.27 1.27)
				)
			)
		)
		(property "Value" ""
			(at 0 0 270)
			(layer "F.Fab")
			(effects
				(font
					(size 1.27 1.27)
				)
			)
		)
		(duplicate_pad_numbers_are_jumpers no)
		(fp_line
			(start -0.7874 0.4064)
			(end -0.7874 -0.4064)
			(stroke
				(width 0.1524)
				(type default)
			)
			(layer "F.SilkS")
		)
		(fp_line
			(start 0.7874 0.4064)
			(end -0.7874 0.4064)
			(stroke
				(width 0.1524)
				(type default)
			)
			(layer "F.SilkS")
		)
		(fp_line
			(start -0.7874 -0.4064)
			(end 0.7874 -0.4064)
			(stroke
				(width 0.1524)
				(type default)
			)
			(layer "F.SilkS")
		)
		(fp_line
			(start 0.7874 -0.4064)
			(end 0.7874 0.4064)
			(stroke
				(width 0.1524)
				(type default)
			)
			(layer "F.SilkS")
		)
		(fp_line
			(start -0.67945 0.3048)
			(end -0.67945 -0.305054)
			(stroke
				(width 0.1)
				(type default)
			)
			(layer "F.Fab")
		)
		(fp_line
			(start -0.12065 0.3048)
			(end -0.67945 0.3048)
			(stroke
				(width 0.1)
				(type default)
			)
			(layer "F.Fab")
		)
		(fp_line
			(start 0.120396 0.3048)
			(end 0.120396 0.2794)
			(stroke
				(width 0.1)
				(type default)
			)
			(layer "F.Fab")
		)
		(fp_line
			(start 0.67945 0.3048)
			(end 0.120396 0.3048)
			(stroke
				(width 0.1)
				(type default)
			)
			(layer "F.Fab")
		)
		(fp_line
			(start -0.12065 0.2794)
			(end -0.12065 0.3048)
			(stroke
				(width 0.1)
				(type default)
			)
			(layer "F.Fab")
		)
		(fp_line
			(start 0.120396 0.2794)
			(end -0.12065 0.2794)
			(stroke
				(width 0.1)
				(type default)
			)
			(layer "F.Fab")
		)
		(fp_line
			(start -0.12065 -0.2794)
			(end 0.12065 -0.2794)
			(stroke
				(width 0.1)
				(type default)
			)
			(layer "F.Fab")
		)
		(fp_line
			(start 0.12065 -0.2794)
			(end 0.12065 -0.3048)
			(stroke
				(width 0.1)
				(type default)
			)
			(layer "F.Fab")
		)
		(fp_line
			(start 0.12065 -0.3048)
			(end 0.67945 -0.3048)
			(stroke
				(width 0.1)
				(type default)
			)
			(layer "F.Fab")
		)
		(fp_line
			(start 0.67945 -0.3048)
			(end 0.67945 0.3048)
			(stroke
				(width 0.1)
				(type default)
			)
			(layer "F.Fab")
		)
		(fp_line
			(start -0.67945 -0.305054)
			(end -0.12065 -0.305054)
			(stroke
				(width 0.1)
				(type default)
			)
			(layer "F.Fab")
		)
		(fp_line
			(start -0.12065 -0.305054)
			(end -0.12065 -0.2794)
			(stroke
				(width 0.1)
				(type default)
			)
			(layer "F.Fab")
		)
		(pad "1" smd circle
			(at -0.40005 0 270)
			(size 0 0)
			(layers "F.Cu" "F.Mask" "F.Paste")
			(net "P1V25_SERDES_VDDPLL_PEX2")
		)
		(pad "2" smd circle
			(at 0.40005 0 270)
			(size 0 0)
			(layers "F.Cu" "F.Mask" "F.Paste")
			(net "P1V25_SERDES_VDDPLL_PEX2_C6")
		)
	)
	(footprint ""
		(layer "F.Cu")
		(at 58.995056 -103.814372 180)
		(property "Reference" "R69"
			(at 0 0 180)
			(layer "F.SilkS")
			(hide yes)
			(effects
				(font
					(size 1.27 1.27)
				)
			)
		)
		(property "Value" ""
			(at 0 0 180)
			(layer "F.Fab")
			(effects
				(font
					(size 1.27 1.27)
				)
			)
		)
		(duplicate_pad_numbers_are_jumpers no)
		(fp_line
			(start 0.7874 0.4064)
			(end -0.7874 0.4064)
			(stroke
				(width 0.1524)
				(type default)
			)
			(layer "F.SilkS")
		)
		(fp_line
			(start 0.7874 -0.4064)
			(end 0.7874 0.4064)
			(stroke
				(width 0.1524)
				(type default)
			)
			(layer "F.SilkS")
		)
		(fp_line
			(start -0.7874 0.4064)
			(end -0.7874 -0.4064)
			(stroke
				(width 0.1524)
				(type default)
			)
			(layer "F.SilkS")
		)
		(fp_line
			(start -0.7874 -0.4064)
			(end 0.7874 -0.4064)
			(stroke
				(width 0.1524)
				(type default)
			)
			(layer "F.SilkS")
		)
		(fp_line
			(start 0.67945 0.3048)
			(end 0.120396 0.3048)
			(stroke
				(width 0.1)
				(type default)
			)
			(layer "F.Fab")
		)
		(fp_line
			(start 0.67945 -0.3048)
			(end 0.67945 0.3048)
			(stroke
				(width 0.1)
				(type default)
			)
			(layer "F.Fab")
		)
		(fp_line
			(start 0.12065 -0.2794)
			(end 0.12065 -0.3048)
			(stroke
				(width 0.1)
				(type default)
			)
			(layer "F.Fab")
		)
		(fp_line
			(start 0.12065 -0.3048)
			(end 0.67945 -0.3048)
			(stroke
				(width 0.1)
				(type default)
			)
			(layer "F.Fab")
		)
		(fp_line
			(start 0.120396 0.3048)
			(end 0.120396 0.2794)
			(stroke
				(width 0.1)
				(type default)
			)
			(layer "F.Fab")
		)
		(fp_line
			(start 0.120396 0.2794)
			(end -0.12065 0.2794)
			(stroke
				(width 0.1)
				(type default)
			)
			(layer "F.Fab")
		)
		(fp_line
			(start -0.12065 0.3048)
			(end -0.67945 0.3048)
			(stroke
				(width 0.1)
				(type default)
			)
			(layer "F.Fab")
		)
		(fp_line
			(start -0.12065 0.2794)
			(end -0.12065 0.3048)
			(stroke
				(width 0.1)
				(type default)
			)
			(layer "F.Fab")
		)
		(fp_line
			(start -0.12065 -0.2794)
			(end 0.12065 -0.2794)
			(stroke
				(width 0.1)
				(type default)
			)
			(layer "F.Fab")
		)
		(fp_line
			(start -0.12065 -0.305054)
			(end -0.12065 -0.2794)
			(stroke
				(width 0.1)
				(type default)
			)
			(layer "F.Fab")
		)
		(fp_line
			(start -0.67945 0.3048)
			(end -0.67945 -0.305054)
			(stroke
				(width 0.1)
				(type default)
			)
			(layer "F.Fab")
		)
		(fp_line
			(start -0.67945 -0.305054)
			(end -0.12065 -0.305054)
			(stroke
				(width 0.1)
				(type default)
			)
			(layer "F.Fab")
		)
		(pad "1" smd circle
			(at -0.40005 0 180)
			(size 0 0)
			(layers "F.Cu" "F.Mask" "F.Paste")
			(net "NCSI_NIC1_TXD0")
		)
		(pad "2" smd circle
			(at 0.40005 0 180)
			(size 0 0)
			(layers "F.Cu" "F.Mask" "F.Paste")
			(net "GND")
		)
	)
	(footprint ""
		(layer "F.Cu")
		(at 128.674876 -251.26569 180)
		(property "Reference" "PR69"
			(at 0 0 180)
			(layer "F.SilkS")
			(hide yes)
			(effects
				(font
					(size 1.27 1.27)
				)
			)
		)
		(property "Value" ""
			(at 0 0 180)
			(layer "F.Fab")
			(effects
				(font
					(size 1.27 1.27)
				)
			)
		)
		(duplicate_pad_numbers_are_jumpers no)
		(fp_line
			(start 0.7874 0.4064)
			(end -0.7874 0.4064)
			(stroke
				(width 0.1524)
				(type default)
			)
			(layer "F.SilkS")
		)
		(fp_line
			(start 0.7874 -0.4064)
			(end 0.7874 0.4064)
			(stroke
				(width 0.1524)
				(type default)
			)
			(layer "F.SilkS")
		)
		(fp_line
			(start -0.7874 0.4064)
			(end -0.7874 -0.4064)
			(stroke
				(width 0.1524)
				(type default)
			)
			(layer "F.SilkS")
		)
		(fp_line
			(start -0.7874 -0.4064)
			(end 0.7874 -0.4064)
			(stroke
				(width 0.1524)
				(type default)
			)
			(layer "F.SilkS")
		)
		(fp_line
			(start 0.67945 0.3048)
			(end 0.120396 0.3048)
			(stroke
				(width 0.1)
				(type default)
			)
			(layer "F.Fab")
		)
		(fp_line
			(start 0.67945 -0.3048)
			(end 0.67945 0.3048)
			(stroke
				(width 0.1)
				(type default)
			)
			(layer "F.Fab")
		)
		(fp_line
			(start 0.12065 -0.2794)
			(end 0.12065 -0.3048)
			(stroke
				(width 0.1)
				(type default)
			)
			(layer "F.Fab")
		)
		(fp_line
			(start 0.12065 -0.3048)
			(end 0.67945 -0.3048)
			(stroke
				(width 0.1)
				(type default)
			)
			(layer "F.Fab")
		)
		(fp_line
			(start 0.120396 0.3048)
			(end 0.120396 0.2794)
			(stroke
				(width 0.1)
				(type default)
			)
			(layer "F.Fab")
		)
		(fp_line
			(start 0.120396 0.2794)
			(end -0.12065 0.2794)
			(stroke
				(width 0.1)
				(type default)
			)
			(layer "F.Fab")
		)
		(fp_line
			(start -0.12065 0.3048)
			(end -0.67945 0.3048)
			(stroke
				(width 0.1)
				(type default)
			)
			(layer "F.Fab")
		)
		(fp_line
			(start -0.12065 0.2794)
			(end -0.12065 0.3048)
			(stroke
				(width 0.1)
				(type default)
			)
			(layer "F.Fab")
		)
		(fp_line
			(start -0.12065 -0.2794)
			(end 0.12065 -0.2794)
			(stroke
				(width 0.1)
				(type default)
			)
			(layer "F.Fab")
		)
		(fp_line
			(start -0.12065 -0.305054)
			(end -0.12065 -0.2794)
			(stroke
				(width 0.1)
				(type default)
			)
			(layer "F.Fab")
		)
		(fp_line
			(start -0.67945 0.3048)
			(end -0.67945 -0.305054)
			(stroke
				(width 0.1)
				(type default)
			)
			(layer "F.Fab")
		)
		(fp_line
			(start -0.67945 -0.305054)
			(end -0.12065 -0.305054)
			(stroke
				(width 0.1)
				(type default)
			)
			(layer "F.Fab")
		)
		(pad "1" smd circle
			(at -0.40005 0 180)
			(size 0 0)
			(layers "F.Cu" "F.Mask" "F.Paste")
			(net "SMB_PJP1_SCL")
		)
		(pad "2" smd circle
			(at 0.40005 0 180)
			(size 0 0)
			(layers "F.Cu" "F.Mask" "F.Paste")
			(net "SMB_BIC_I2C6_MUX_VR_R_SCL")
		)
	)
	(footprint ""
		(layer "F.Cu")
		(at 231.412288 -97.258378 -90)
		(property "Reference" "R1016"
			(at 0 0 270)
			(layer "F.SilkS")
			(hide yes)
			(effects
				(font
					(size 1.27 1.27)
				)
			)
		)
		(property "Value" ""
			(at 0 0 270)
			(layer "F.Fab")
			(effects
				(font
					(size 1.27 1.27)
				)
			)
		)
		(duplicate_pad_numbers_are_jumpers no)
		(fp_line
			(start -0.7874 0.4064)
			(end -0.7874 -0.4064)
			(stroke
				(width 0.1524)
				(type default)
			)
			(layer "F.SilkS")
		)
		(fp_line
			(start 0.7874 0.4064)
			(end -0.7874 0.4064)
			(stroke
				(width 0.1524)
				(type default)
			)
			(layer "F.SilkS")
		)
		(fp_line
			(start -0.7874 -0.4064)
			(end 0.7874 -0.4064)
			(stroke
				(width 0.1524)
				(type default)
			)
			(layer "F.SilkS")
		)
		(fp_line
			(start 0.7874 -0.4064)
			(end 0.7874 0.4064)
			(stroke
				(width 0.1524)
				(type default)
			)
			(layer "F.SilkS")
		)
		(fp_line
			(start -0.67945 0.3048)
			(end -0.67945 -0.305054)
			(stroke
				(width 0.1)
				(type default)
			)
			(layer "F.Fab")
		)
		(fp_line
			(start -0.12065 0.3048)
			(end -0.67945 0.3048)
			(stroke
				(width 0.1)
				(type default)
			)
			(layer "F.Fab")
		)
		(fp_line
			(start 0.120396 0.3048)
			(end 0.120396 0.2794)
			(stroke
				(width 0.1)
				(type default)
			)
			(layer "F.Fab")
		)
		(fp_line
			(start 0.67945 0.3048)
			(end 0.120396 0.3048)
			(stroke
				(width 0.1)
				(type default)
			)
			(layer "F.Fab")
		)
		(fp_line
			(start -0.12065 0.2794)
			(end -0.12065 0.3048)
			(stroke
				(width 0.1)
				(type default)
			)
			(layer "F.Fab")
		)
		(fp_line
			(start 0.120396 0.2794)
			(end -0.12065 0.2794)
			(stroke
				(width 0.1)
				(type default)
			)
			(layer "F.Fab")
		)
		(fp_line
			(start -0.12065 -0.2794)
			(end 0.12065 -0.2794)
			(stroke
				(width 0.1)
				(type default)
			)
			(layer "F.Fab")
		)
		(fp_line
			(start 0.12065 -0.2794)
			(end 0.12065 -0.3048)
			(stroke
				(width 0.1)
				(type default)
			)
			(layer "F.Fab")
		)
		(fp_line
			(start 0.12065 -0.3048)
			(end 0.67945 -0.3048)
			(stroke
				(width 0.1)
				(type default)
			)
			(layer "F.Fab")
		)
		(fp_line
			(start 0.67945 -0.3048)
			(end 0.67945 0.3048)
			(stroke
				(width 0.1)
				(type default)
			)
			(layer "F.Fab")
		)
		(fp_line
			(start -0.67945 -0.305054)
			(end -0.12065 -0.305054)
			(stroke
				(width 0.1)
				(type default)
			)
			(layer "F.Fab")
		)
		(fp_line
			(start -0.12065 -0.305054)
			(end -0.12065 -0.2794)
			(stroke
				(width 0.1)
				(type default)
			)
			(layer "F.Fab")
		)
		(pad "1" smd circle
			(at -0.40005 0 270)
			(size 0 0)
			(layers "F.Cu" "F.Mask" "F.Paste")
			(net "P3V3_AUX")
		)
		(pad "2" smd circle
			(at 0.40005 0 270)
			(size 0 0)
			(layers "F.Cu" "F.Mask" "F.Paste")
			(net "PEX_USB_HUB_OVCUR3")
		)
	)
)
